FILE_TYPE = MACRO_DRAWING;
SET COLOR_WIRE YELLOW;
SET COLOR_PROP MONO;
SET COLOR_DOT WHITE;
SET COLOR_ARC YELLOW;
SET COLOR_BODY GREEN;
SET COLOR_NOTE MONO;
SET PROP_DISPLAY VALUE;
SET PAGE_NUMBER P10;
FORCEADD INTEL_CORP_BPAGE..1
(4250 200);
FORCEPROP 1 LAST CDS_CON_LAST_MODIFIED Fri Jun 16 17:48:00 2017
J 0
(2825 525);
PAINT ORANGE (2825 525);
DISPLAY INVISIBLE (2825 525);
FORCEPROP 1 LAST CUSTOM_TXT_CDS <CURRENT_DESIGN_SHEET> OF <TOTAL_DESIGN_SHEETS>
J 0
(3750 225);
PAINT ORANGE (3750 225);
FORCEPROP 1 LAST CUSTOM_TXT_CDS <CON_LAST_MODIFIED>
J 0
(250 300);
PAINT ORANGE (250 300);
FORCEPROP 2 LAST CUSTOM_TXT_CDS <XR_PAGE_TITLE>
J 0
(-3640 5450);
DISPLAY 0.638298 (-3640 5450);
PAINT PINK (-3640 5450);
DISPLAY INVISIBLE (-3640 5450);
FORCEPROP 1 LAST SCH_TITLE INTERRUPTS AND ERROR PROPAGATION
J 0
(-3700 250);
DISPLAY 1.212766 (-3700 250);
PAINT ORANGE (-3700 250);
FORCEPROP 2 LAST PAGE_BORDER TRUE
J 0
(-3640 5450);
DISPLAY 0.638298 (-3640 5450);
PAINT PINK (-3640 5450);
DISPLAY INVISIBLE (-3640 5450);
FORCEPROP 2 LAST CDS_LIB mstr_symbols
J 0
(4250 200);
PAINT MONO (4250 200);
DISPLAY INVISIBLE (4250 200);
FORCEPROP 1 LAST COMMENT_BODY TRUE
J 0
(4262 212);
DISPLAY 0.468085 (4262 212);
PAINT GREEN (4262 212);
DISPLAY INVISIBLE (4262 212);
FORCEPROP 2 LAST CDS_XR_PAGE_TITLE CR-10 : @BASEBOARD_FAB2_LIB.BASEBOARD_FAB2(SCH_1):PAGE10
J 0
(-3640 5450);
DISPLAY 0.638298 (-3640 5450);
PAINT PINK (-3640 5450);
DISPLAY INVISIBLE (-3640 5450);
FORCENOTE
$CDS_IMAGE|Interrupts_and_Error_20160411.jpg|5414|6500
(225 2775) 1;
DISPLAY LEFT (225 2775);
QUIT
